# Thunderbolt PCIe Adaper — assets/stackup.csv
Name;Type;Material;Thickness[mm];Constant
F.Mask;Top Solder Mask;;0.01;
F.Cu;copper;;0.035;
dielectric 1;prepreg;PR2116;0.12;4.12
In1.Cu;copper;;0.018;
dielectric 2;core;FR4-Improved;0.51;4.125
In2.Cu;copper;;0.018;
dielectric 3;prepreg;PR1080;0.14;4.125
In3.Cu;copper;;0.018;
dielectric 4;core;FR4-Improved;0.51;4.125
In4.Cu;copper;;0.018;
dielectric 5;prepreg;PR2116;0.12;4.12
B.Cu;copper;;0.035;
B.Mask;Bottom Solder Mask;;0.01;
